FILE_TYPE = MACRO_DRAWING;
SET COLOR_WIRE YELLOW;
SET COLOR_PROP MONO;
SET COLOR_DOT WHITE;
SET COLOR_ARC YELLOW;
SET COLOR_BODY GREEN;
SET COLOR_NOTE MONO;
SET PROP_DISPLAY VALUE;
SET PAGE_NUMBER P5;
FORCEADD INTEL_CORP_BPAGE..1
(12900 -100);
FORCEPROP 1 LAST CDS_CON_LAST_MODIFIED Fri Jun 16 17:47:56 2017
J 0
(11475 225);
PAINT ORANGE (11475 225);
DISPLAY INVISIBLE (11475 225);
FORCEPROP 1 LAST CUSTOM_TXT_CDS <CURRENT_DESIGN_SHEET> OF <TOTAL_DESIGN_SHEETS>
J 0
(12400 -75);
PAINT ORANGE (12400 -75);
FORCEPROP 1 LAST CUSTOM_TXT_CDS <CON_LAST_MODIFIED>
J 0
(8900 0);
PAINT ORANGE (8900 0);
FORCEPROP 2 LAST CUSTOM_TXT_CDS <XR_PAGE_TITLE>
J 0
(5010 5150);
DISPLAY 0.638298 (5010 5150);
PAINT PINK (5010 5150);
DISPLAY INVISIBLE (5010 5150);
FORCEPROP 1 LAST SCH_TITLE SYSTEM BLOCK DIAGRAM
J 0
(4950 -50);
DISPLAY 1.212766 (4950 -50);
PAINT ORANGE (4950 -50);
FORCEPROP 2 LAST PAGE_BORDER TRUE
J 0
(5010 5150);
DISPLAY 0.638298 (5010 5150);
PAINT PINK (5010 5150);
DISPLAY INVISIBLE (5010 5150);
FORCEPROP 2 LAST CDS_LIB mstr_symbols
J 0
(12900 -100);
PAINT MONO (12900 -100);
DISPLAY INVISIBLE (12900 -100);
FORCEPROP 1 LAST COMMENT_BODY TRUE
J 0
(12912 -88);
DISPLAY 0.468085 (12912 -88);
PAINT GREEN (12912 -88);
DISPLAY INVISIBLE (12912 -88);
FORCEPROP 2 LAST CDS_XR_PAGE_TITLE CR-5 : @BASEBOARD_FAB2_LIB.BASEBOARD_FAB2(SCH_1):PAGE5
J 0
(5010 5150);
DISPLAY 0.638298 (5010 5150);
PAINT PINK (5010 5150);
DISPLAY INVISIBLE (5010 5150);
FORCENOTE
$CDS_IMAGE|TiogaPass_SYSTEM_Block_diagram_20170210_1.jpg|5500|5500
(8875 2250) 0;
DISPLAY LEFT (8875 2250);
QUIT
